# BASEBOARD_FAB2 (Tioga Pass) — schematic netlist excerpt (pin names and nets, part order shuffled) for the footprints in the layout excerpt that follows; sources: Cadence DE-HDL packaged netlist, KiCad conversion of Wiwynn_Tioga_Pass_MB.brd

R8W9  RES  4.75K 1% CHIP  pkg 0402  page 89 : A = P3V3_STBY ; B = IRQ_DIMM_SAVE_LVT3_CPU1
C7P4  CAP  100UF 4V 20% X5R  pkg 0805  page 76 : A = PVCCMCP_CPU1 ; B = GND
R25W40  120R2F-GP  1%  pkg RCL_GP  page 151 : \1\ = BMC_M_A2 ; \2\ = P1V2_AUX_BMC

(kicad_pcb
	(version 20260206)
	(generator "pcbnew")
	(generator_version "10.0")
	(general
		(thickness 1.6)
		(legacy_teardrops no)
	)
	(paper "A4")
	(title_block
		(title "Wiwynn_Tioga_Pass_MB.brd")
		(comment 1 "Tioga Pass / footprints 3747-3749 of 4770")
	)
	(layers
		(0 "F.Cu" signal "TOP")
		(4 "In1.Cu" signal "L2GND")
		(6 "In2.Cu" signal "L3")
		(8 "In3.Cu" signal "L4GND")
		(10 "In4.Cu" signal "L5")
		(12 "In5.Cu" signal "L6GND")
		(14 "In6.Cu" signal "L7VCC")
		(16 "In7.Cu" signal "L8VCC")
		(18 "In8.Cu" signal "L9GND")
		(20 "In9.Cu" signal "L10")
		(22 "In10.Cu" signal "L11GND")
		(24 "In11.Cu" signal "L12")
		(26 "In12.Cu" signal "L13GND")
		(2 "B.Cu" signal "BOTTOM")
		(9 "F.Adhes" user "F.Adhesive")
		(11 "B.Adhes" user "B.Adhesive")
		(13 "F.Paste" user "Package Geometry/Pastemask Top")
		(15 "B.Paste" user "Package Geometry/Pastemask Bottom")
		(5 "F.SilkS" user "Ref Des/Silkscreen Top")
		(7 "B.SilkS" user "Ref Des/Silkscreen Bottom")
		(1 "F.Mask" user "Board Geometry/Soldermask Top")
		(3 "B.Mask" user "Board Geometry/Soldermask Bottom")
		(17 "Dwgs.User" user "User.Drawings")
		(19 "Cmts.User" user "User.Comments")
		(21 "Eco1.User" user "User.Eco1")
		(23 "Eco2.User" user "User.Eco2")
		(25 "Edge.Cuts" user "Board Geometry/Outline")
		(27 "Margin" user)
		(31 "F.CrtYd" user "Package Geometry/Place Bound Top")
		(29 "B.CrtYd" user "Package Geometry/Place Bound Bottom")
		(35 "F.Fab" user "Ref Des/Assembly Top")
		(33 "B.Fab" user "Ref Des/Assembly Bottom")
	)
	(footprint ""
		(layer "B.Cu")
		(at 114.046254 -79.60614 180)
		(property "Reference" "C7P4"
			(at 0 0 0)
			(layer "B.SilkS")
			(hide yes)
			(effects
				(font
					(size 1.27 1.27)
				)
				(justify mirror)
			)
		)
		(property "Value" ""
			(at 0 0 0)
			(layer "B.Fab")
			(effects
				(font
					(size 1.27 1.27)
				)
				(justify mirror)
			)
		)
		(duplicate_pad_numbers_are_jumpers no)
		(fp_poly
			(pts
				(xy 0.7239 -0.2159) (xy -0.7239 -0.2159) (xy -0.7239 1.9939) (xy 0.7239 1.9939)
			)
			(stroke
				(width 0)
				(type default)
			)
			(fill no)
			(layer "B.CrtYd")
		)
		(fp_line
			(start 0.7239 1.9939)
			(end -0.7239 1.9939)
			(stroke
				(width 0.1)
				(type default)
			)
			(layer "B.Fab")
		)
		(fp_line
			(start 0.7239 -0.2159)
			(end 0.7239 1.9939)
			(stroke
				(width 0.1)
				(type default)
			)
			(layer "B.Fab")
		)
		(fp_line
			(start -0.7239 1.9939)
			(end -0.7239 -0.2159)
			(stroke
				(width 0.1)
				(type default)
			)
			(layer "B.Fab")
		)
		(fp_line
			(start -0.7239 -0.2159)
			(end 0.7239 -0.2159)
			(stroke
				(width 0.1)
				(type default)
			)
			(layer "B.Fab")
		)
		(pad "1" smd rect
			(at 0 0)
			(size 1.27 1.016)
			(layers "B.Cu" "B.Mask" "B.Paste")
			(net "PVCCMCP_CPU1")
		)
		(pad "2" smd rect
			(at 0 1.778)
			(size 1.27 1.016)
			(layers "B.Cu" "B.Mask" "B.Paste")
			(net "GND")
		)
		(zone
			(layer "B.Cu")
			(hatch none 0.5)
			(connect_pads
				(clearance 0)
			)
			(min_thickness 0.25)
			(keepout
				(tracks not_allowed)
				(vias allowed)
				(pads allowed)
				(copperpour not_allowed)
				(footprints allowed)
			)
			(placement
				(enabled no)
				(sheetname "")
			)
			(fill
				(thermal_gap 0.5)
				(thermal_bridge_width 0.5)
				(island_removal_mode 0)
			)
			(polygon
				(pts
					(xy 113.411254 -80.11414) (xy 114.681254 -80.11414) (xy 114.681254 -80.87614) (xy 113.411254 -80.87614)
				)
			)
		)
	)
	(footprint ""
		(layer "B.Cu")
		(at 442.262006 -43.54195 180)
		(property "Reference" "R25W40"
			(at 0 0 0)
			(layer "B.SilkS")
			(hide yes)
			(effects
				(font
					(size 1.27 1.27)
				)
				(justify mirror)
			)
		)
		(property "Value" "*"
			(at -0.064008 -4.108196 180)
			(unlocked yes)
			(layer "B.Fab")
			(hide yes)
			(effects
				(font
					(size 1.27 1.016)
					(thickness 0.1524)
				)
				(justify mirror)
			)
		)
		(property "Device Type" "120R2F-GP_RCL_GP-120R2F-GP,64.A"
			(at -0.064008 -5.632196 180)
			(unlocked yes)
			(layer "B.Fab")
			(hide yes)
			(effects
				(font
					(size 1.27 1.016)
					(thickness 0.1524)
				)
				(justify mirror)
			)
		)
		(duplicate_pad_numbers_are_jumpers no)
		(fp_line
			(start 0.508 -0.9398)
			(end 0.508 0.9398)
			(stroke
				(width 0.1524)
				(type default)
			)
			(layer "B.SilkS")
		)
		(fp_line
			(start -0.508 -0.9398)
			(end 0.508 -0.9398)
			(stroke
				(width 0.1524)
				(type default)
			)
			(layer "B.SilkS")
		)
		(fp_rect
			(start 0.508 0.9398)
			(end -0.508 -0.9398)
			(stroke
				(width 0)
				(type default)
			)
			(fill no)
			(layer "B.CrtYd")
		)
		(fp_rect
			(start 0.508 0.9398)
			(end -0.508 -0.9398)
			(stroke
				(width 0)
				(type default)
			)
			(fill no)
			(layer "B.Fab")
		)
		(pad "1" smd custom
			(at 0 -0.4445)
			(size 0.1397 0.1397)
			(layers "B.Cu" "B.Mask" "B.Paste")
			(net "BMC_M_A2")
			(options
				(clearance outline)
				(anchor circle)
			)
			(primitives
				(gr_poly
					(pts
						(arc
							(start -0.1778 0.2794)
							(mid -0.249642 0.249642)
							(end -0.2794 0.1778)
						)
						(arc
							(start -0.2794 -0.1778)
							(mid -0.249642 -0.249642)
							(end -0.1778 -0.2794)
						)
						(arc
							(start 0.1778 -0.2794)
							(mid 0.249642 -0.249642)
							(end 0.2794 -0.1778)
						)
						(arc
							(start 0.2794 0.1778)
							(mid 0.249642 0.249642)
							(end 0.1778 0.2794)
						)
					)
					(width 0)
					(fill yes)
				)
			)
		)
		(pad "2" smd custom
			(at 0 0.4445)
			(size 0.1397 0.1397)
			(layers "B.Cu" "B.Mask" "B.Paste")
			(net "P1V2_AUX_BMC")
			(options
				(clearance outline)
				(anchor circle)
			)
			(primitives
				(gr_poly
					(pts
						(arc
							(start -0.1778 0.2794)
							(mid -0.249642 0.249642)
							(end -0.2794 0.1778)
						)
						(arc
							(start -0.2794 -0.1778)
							(mid -0.249642 -0.249642)
							(end -0.1778 -0.2794)
						)
						(arc
							(start 0.1778 -0.2794)
							(mid 0.249642 -0.249642)
							(end 0.2794 -0.1778)
						)
						(arc
							(start 0.2794 0.1778)
							(mid 0.249642 0.249642)
							(end 0.1778 0.2794)
						)
					)
					(width 0)
					(fill yes)
				)
			)
		)
	)
	(footprint ""
		(layer "B.Cu")
		(at 309.436516 -28.944824)
		(property "Reference" "R8W9"
			(at 0.8382 -0.67818 0)
			(unlocked yes)
			(layer "B.SilkS")
			(effects
				(font
					(size 0.4064 0.254)
					(thickness 0.1524)
				)
				(justify left mirror)
			)
		)
		(property "Value" ""
			(at 0 0 0)
			(layer "B.Fab")
			(effects
				(font
					(size 1.27 1.27)
				)
				(justify mirror)
			)
		)
		(duplicate_pad_numbers_are_jumpers no)
		(fp_poly
			(pts
				(xy 0.2794 -0.1016) (xy -0.2794 -0.1016) (xy -0.2794 0.9906) (xy 0.2794 0.9906)
			)
			(stroke
				(width 0)
				(type default)
			)
			(fill no)
			(layer "B.CrtYd")
		)
		(fp_line
			(start -0.2794 -0.1016)
			(end 0.2794 -0.1016)
			(stroke
				(width 0.1)
				(type default)
			)
			(layer "B.Fab")
		)
		(fp_line
			(start -0.2794 0.9906)
			(end -0.2794 -0.1016)
			(stroke
				(width 0.1)
				(type default)
			)
			(layer "B.Fab")
		)
		(fp_line
			(start 0.2794 -0.1016)
			(end 0.2794 0.9906)
			(stroke
				(width 0.1)
				(type default)
			)
			(layer "B.Fab")
		)
		(fp_line
			(start 0.2794 0.9906)
			(end -0.2794 0.9906)
			(stroke
				(width 0.1)
				(type default)
			)
			(layer "B.Fab")
		)
		(pad "1" smd rect
			(at 0 0 180)
			(size 0.508 0.508)
			(layers "B.Cu" "B.Mask" "B.Paste")
			(net "P3V3_STBY")
		)
		(pad "2" smd rect
			(at 0 0.889 180)
			(size 0.508 0.508)
			(layers "B.Cu" "B.Mask" "B.Paste")
			(net "IRQ_DIMM_SAVE_LVT3_CPU1")
		)
		(zone
			(layer "B.Cu")
			(hatch none 0.5)
			(connect_pads
				(clearance 0)
			)
			(min_thickness 0.25)
			(keepout
				(tracks allowed)
				(vias not_allowed)
				(pads allowed)
				(copperpour not_allowed)
				(footprints allowed)
			)
			(placement
				(enabled no)
				(sheetname "")
			)
			(fill
				(thermal_gap 0.5)
				(thermal_bridge_width 0.5)
				(island_removal_mode 0)
			)
			(polygon
				(pts
					(xy 309.690516 -28.690824) (xy 309.182516 -28.690824) (xy 309.182516 -28.309824) (xy 309.690516 -28.309824)
				)
			)
		)
		(zone
			(layer "B.Cu")
			(hatch none 0.5)
			(connect_pads
				(clearance 0)
			)
			(min_thickness 0.25)
			(keepout
				(tracks not_allowed)
				(vias allowed)
				(pads allowed)
				(copperpour not_allowed)
				(footprints allowed)
			)
			(placement
				(enabled no)
				(sheetname "")
			)
			(fill
				(thermal_gap 0.5)
				(thermal_bridge_width 0.5)
				(island_removal_mode 0)
			)
			(polygon
				(pts
					(xy 309.690516 -28.309824) (xy 309.182516 -28.309824) (xy 309.182516 -28.690824) (xy 309.690516 -28.690824)
				)
			)
		)
	)
)
